(kicad_pcb
	(version 20260206)
	(generator "pcbnew")
	(generator_version "10.0")
	(general
		(thickness 1.6)
		(legacy_teardrops no)
	)
	(paper "A4")
	(title_block
		(title "03242023_DA0F0TMBIJ0_F0T_Motherboard_J_brd_V01_OCP.brd")
		(comment 1 "Grand Teton / footprints 3729-3733 of 6105")
	)
	(layers
		(0 "F.Cu" signal "TOP")
		(4 "In1.Cu" signal "GND")
		(6 "In2.Cu" signal "IN1")
		(8 "In3.Cu" signal "GND1")
		(10 "In4.Cu" signal "IN2")
		(12 "In5.Cu" signal "GND2")
		(14 "In6.Cu" signal "IN3")
		(16 "In7.Cu" signal "GND3")
		(18 "In8.Cu" signal "VCC")
		(20 "In9.Cu" signal "VCC1")
		(22 "In10.Cu" signal "GND4")
		(24 "In11.Cu" signal "IN4")
		(26 "In12.Cu" signal "GND5")
		(28 "In13.Cu" signal "IN5")
		(30 "In14.Cu" signal "GND6")
		(32 "In15.Cu" signal "IN6")
		(34 "In16.Cu" signal "GND7")
		(2 "B.Cu" signal "BOTTOM")
		(9 "F.Adhes" user "F.Adhesive")
		(11 "B.Adhes" user "B.Adhesive")
		(13 "F.Paste" user "Package Geometry/Pastemask Top")
		(15 "B.Paste" user "Package Geometry/Pastemask Bottom")
		(5 "F.SilkS" user "Ref Des/Silkscreen Top")
		(7 "B.SilkS" user "Ref Des/Silkscreen Bottom")
		(1 "F.Mask" user "Board Geometry/Soldermask Top")
		(3 "B.Mask" user "Board Geometry/Soldermask Bottom")
		(17 "Dwgs.User" user "User.Drawings")
		(19 "Cmts.User" user "User.Comments")
		(21 "Eco1.User" user "User.Eco1")
		(23 "Eco2.User" user "User.Eco2")
		(25 "Edge.Cuts" user "Board Geometry/Outline")
		(27 "Margin" user)
		(31 "F.CrtYd" user "Package Geometry/Place Bound Top")
		(29 "B.CrtYd" user "Package Geometry/Place Bound Bottom")
		(35 "F.Fab" user "Ref Des/Assembly Top")
		(33 "B.Fab" user "Ref Des/Assembly Bottom")
	)
	(footprint ""
		(layer "F.Cu")
		(at 232.176066 -402.722842 180)
		(property "Reference" "PU297"
			(at 0.384556 7.701788 0)
			(unlocked yes)
			(layer "F.SilkS")
			(effects
				(font
					(size 0.7874 0.5842)
					(thickness 0.1524)
				)
			)
		)
		(property "Value" ""
			(at 0 0 180)
			(layer "F.Fab")
			(effects
				(font
					(size 1.27 1.27)
				)
			)
		)
		(duplicate_pad_numbers_are_jumpers no)
		(fp_line
			(start 2.567686 2.567686)
			(end 2.567686 -2.567686)
			(stroke
				(width 0.1524)
				(type default)
			)
			(layer "F.SilkS")
		)
		(fp_line
			(start 2.567686 -2.567686)
			(end -2.567686 -2.567686)
			(stroke
				(width 0.1524)
				(type default)
			)
			(layer "F.SilkS")
		)
		(fp_line
			(start -2.567686 2.567686)
			(end 2.567686 2.567686)
			(stroke
				(width 0.1524)
				(type default)
			)
			(layer "F.SilkS")
		)
		(fp_line
			(start -2.567686 -2.567686)
			(end -2.567686 2.567686)
			(stroke
				(width 0.1524)
				(type default)
			)
			(layer "F.SilkS")
		)
		(fp_poly
			(pts
				(xy -3.429 -3.101594) (xy -3.06959 -2.024126) (xy -4.147312 -2.383282)
			)
			(stroke
				(width 0)
				(type default)
			)
			(fill yes)
			(layer "F.SilkS")
		)
		(fp_line
			(start 2.549906 2.549906)
			(end 2.549906 -2.549906)
			(stroke
				(width 0.1)
				(type default)
			)
			(layer "F.Fab")
		)
		(fp_line
			(start 2.549906 -2.549906)
			(end -2.549906 -2.549906)
			(stroke
				(width 0.1)
				(type default)
			)
			(layer "F.Fab")
		)
		(fp_line
			(start -2.549906 2.549906)
			(end 2.549906 2.549906)
			(stroke
				(width 0.1)
				(type default)
			)
			(layer "F.Fab")
		)
		(fp_line
			(start -2.549906 -2.549906)
			(end -2.549906 2.549906)
			(stroke
				(width 0.1)
				(type default)
			)
			(layer "F.Fab")
		)
		(fp_poly
			(pts
				(xy -3.806698 -2.25806) (xy -3.806698 -1.24206) (xy -2.790698 -1.75006)
			)
			(stroke
				(width 0)
				(type default)
			)
			(fill yes)
			(layer "F.Fab")
		)
		(pad "1" smd rect
			(at -2.250186 -1.75006 270)
			(size 0.254 0.3556)
			(layers "F.Cu" "F.Mask" "F.Paste")
			(net "P12V_AUX")
		)
		(pad "2" smd rect
			(at -2.237486 -1.249934 270)
			(size 0.254 0.381)
			(layers "F.Cu" "F.Mask" "F.Paste")
			(net "P12V_AUX")
		)
		(pad "3" smd rect
			(at -2.237486 -0.750062 270)
			(size 0.254 0.381)
			(layers "F.Cu" "F.Mask" "F.Paste")
			(net "HSC_D_OC_4")
		)
		(pad "4" smd rect
			(at -2.237486 -0.249936 270)
			(size 0.254 0.381)
			(layers "F.Cu" "F.Mask" "F.Paste")
			(net "HSC_ON")
		)
		(pad "5" smd rect
			(at -2.237486 0.249936 270)
			(size 0.254 0.381)
			(layers "F.Cu" "F.Mask" "F.Paste")
			(net "HSC_FAULT")
		)
		(pad "6" smd rect
			(at -2.237486 0.750062 270)
			(size 0.254 0.381)
			(layers "F.Cu" "F.Mask" "F.Paste")
			(net "HSC_FLT_TYPE_4")
		)
		(pad "7" smd rect
			(at -2.237486 1.249934 270)
			(size 0.254 0.381)
			(layers "F.Cu" "F.Mask" "F.Paste")
			(net "HSC_NC1_4")
		)
		(pad "8" smd rect
			(at -2.250186 1.75006 270)
			(size 0.254 0.3556)
			(layers "F.Cu" "F.Mask" "F.Paste")
			(net "HSC_MODE_4")
		)
		(pad "9" smd rect
			(at -1.75006 2.250186 180)
			(size 0.254 0.3556)
			(layers "F.Cu" "F.Mask" "F.Paste")
			(net "P12V_PSU")
		)
		(pad "10" smd rect
			(at -1.249934 2.237486 180)
			(size 0.254 0.381)
			(layers "F.Cu" "F.Mask" "F.Paste")
			(net "P12V_PSU")
		)
		(pad "11" smd rect
			(at -0.750062 2.237486 180)
			(size 0.254 0.381)
			(layers "F.Cu" "F.Mask" "F.Paste")
			(net "P12V_PSU")
		)
		(pad "12" smd rect
			(at -0.249936 2.237486 180)
			(size 0.254 0.381)
			(layers "F.Cu" "F.Mask" "F.Paste")
			(net "P12V_PSU")
		)
		(pad "13" smd rect
			(at 0.249936 2.237486 180)
			(size 0.254 0.381)
			(layers "F.Cu" "F.Mask" "F.Paste")
			(net "P12V_PSU")
		)
		(pad "14" smd rect
			(at 0.750062 2.237486 180)
			(size 0.254 0.381)
			(layers "F.Cu" "F.Mask" "F.Paste")
			(net "P12V_PSU")
		)
		(pad "15" smd rect
			(at 1.249934 2.237486 180)
			(size 0.254 0.381)
			(layers "F.Cu" "F.Mask" "F.Paste")
			(net "P12V_PSU")
		)
		(pad "16" smd rect
			(at 1.75006 2.250186 180)
			(size 0.254 0.3556)
			(layers "F.Cu" "F.Mask" "F.Paste")
			(net "P12V_PSU")
		)
		(pad "17" smd rect
			(at 2.250186 1.75006 270)
			(size 0.254 0.3556)
			(layers "F.Cu" "F.Mask" "F.Paste")
			(net "HSC_SCREF_4")
		)
		(pad "18" smd rect
			(at 2.237486 1.249934 270)
			(size 0.254 0.381)
			(layers "F.Cu" "F.Mask" "F.Paste")
			(net "HSC_VTEMP")
		)
		(pad "19" smd rect
			(at 2.237486 0.750062 270)
			(size 0.254 0.381)
			(layers "F.Cu" "F.Mask" "F.Paste")
			(net "HSC_SS")
		)
		(pad "20" smd rect
			(at 2.237486 0.249936 270)
			(size 0.254 0.381)
			(layers "F.Cu" "F.Mask" "F.Paste")
			(net "AGND_HSC")
		)
		(pad "21" smd rect
			(at 2.237486 -0.249936 270)
			(size 0.254 0.381)
			(layers "F.Cu" "F.Mask" "F.Paste")
			(net "HSC_VDD_R_4")
		)
		(pad "22" smd rect
			(at 2.237486 -0.750062 270)
			(size 0.254 0.381)
			(layers "F.Cu" "F.Mask" "F.Paste")
			(net "HSC_IMON")
		)
		(pad "23" smd rect
			(at 2.237486 -1.249934 270)
			(size 0.254 0.381)
			(layers "F.Cu" "F.Mask" "F.Paste")
			(net "HSC_CS_4")
		)
		(pad "24" smd rect
			(at 2.250186 -1.75006 270)
			(size 0.254 0.3556)
			(layers "F.Cu" "F.Mask" "F.Paste")
			(net "HSC_OCREF")
		)
		(pad "25" smd rect
			(at 1.75006 -2.250186 180)
			(size 0.254 0.3556)
			(layers "F.Cu" "F.Mask" "F.Paste")
			(net "P12V_AUX")
		)
		(pad "26" smd rect
			(at 1.249934 -2.237486 180)
			(size 0.254 0.381)
			(layers "F.Cu" "F.Mask" "F.Paste")
			(net "P12V_AUX")
		)
		(pad "27" smd rect
			(at 0.750062 -2.237486 180)
			(size 0.254 0.381)
			(layers "F.Cu" "F.Mask" "F.Paste")
			(net "P12V_AUX")
		)
		(pad "28" smd rect
			(at 0.249936 -2.237486 180)
			(size 0.254 0.381)
			(layers "F.Cu" "F.Mask" "F.Paste")
			(net "P12V_AUX")
		)
		(pad "29" smd rect
			(at -0.249936 -2.237486 180)
			(size 0.254 0.381)
			(layers "F.Cu" "F.Mask" "F.Paste")
			(net "P12V_AUX")
		)
		(pad "30" smd rect
			(at -0.750062 -2.237486 180)
			(size 0.254 0.381)
			(layers "F.Cu" "F.Mask" "F.Paste")
			(net "P12V_AUX")
		)
		(pad "31" smd rect
			(at -1.249934 -2.237486 180)
			(size 0.254 0.381)
			(layers "F.Cu" "F.Mask" "F.Paste")
			(net "P12V_AUX")
		)
		(pad "32" smd rect
			(at -1.75006 -2.250186 180)
			(size 0.254 0.3556)
			(layers "F.Cu" "F.Mask" "F.Paste")
			(net "P12V_AUX")
		)
		(pad "33" smd rect
			(at 0 0 180)
			(size 3.4036 3.4036)
			(layers "F.Cu" "F.Mask" "F.Paste")
			(net "P12V_PSU")
		)
		(zone
			(layer "F.Cu")
			(hatch none 0.5)
			(connect_pads
				(clearance 0)
			)
			(min_thickness 0.25)
			(keepout
				(tracks not_allowed)
				(vias allowed)
				(pads allowed)
				(copperpour not_allowed)
				(footprints allowed)
			)
			(placement
				(enabled no)
				(sheetname "")
			)
			(fill
				(thermal_gap 0.5)
				(thermal_bridge_width 0.5)
				(island_removal_mode 0)
			)
			(polygon
				(pts
					(xy 234.197652 -401.275042) (xy 234.197652 -400.825208) (xy 234.0737 -400.701256) (xy 233.623866 -400.701256)
					(xy 233.623866 -400.726656) (xy 230.728266 -400.726656) (xy 230.728266 -400.701256) (xy 230.15448 -400.701256)
					(xy 230.15448 -401.275042) (xy 230.17988 -401.275042) (xy 230.17988 -404.170642) (xy 230.15448 -404.170642)
					(xy 230.15448 -404.475442) (xy 230.423466 -404.475442) (xy 230.423466 -400.970242) (xy 233.928666 -400.970242)
					(xy 233.928666 -403.230842) (xy 234.172252 -403.230842) (xy 234.172252 -401.275042)
				)
			)
		)
	)
	(footprint ""
		(layer "F.Cu")
		(at 185.22188 -126.964948 -90)
		(property "Reference" "R270"
			(at 0 0 270)
			(layer "F.SilkS")
			(hide yes)
			(effects
				(font
					(size 1.27 1.27)
				)
			)
		)
		(property "Value" ""
			(at 0 0 270)
			(layer "F.Fab")
			(effects
				(font
					(size 1.27 1.27)
				)
			)
		)
		(duplicate_pad_numbers_are_jumpers no)
		(fp_line
			(start -0.7874 0.4064)
			(end -0.7874 -0.4064)
			(stroke
				(width 0.1524)
				(type default)
			)
			(layer "F.SilkS")
		)
		(fp_line
			(start 0.7874 0.4064)
			(end -0.7874 0.4064)
			(stroke
				(width 0.1524)
				(type default)
			)
			(layer "F.SilkS")
		)
		(fp_line
			(start -0.7874 -0.4064)
			(end 0.7874 -0.4064)
			(stroke
				(width 0.1524)
				(type default)
			)
			(layer "F.SilkS")
		)
		(fp_line
			(start 0.7874 -0.4064)
			(end 0.7874 0.4064)
			(stroke
				(width 0.1524)
				(type default)
			)
			(layer "F.SilkS")
		)
		(fp_line
			(start -0.67945 0.3048)
			(end -0.67945 -0.305054)
			(stroke
				(width 0.1)
				(type default)
			)
			(layer "F.Fab")
		)
		(fp_line
			(start -0.12065 0.3048)
			(end -0.67945 0.3048)
			(stroke
				(width 0.1)
				(type default)
			)
			(layer "F.Fab")
		)
		(fp_line
			(start 0.120396 0.3048)
			(end 0.120396 0.2794)
			(stroke
				(width 0.1)
				(type default)
			)
			(layer "F.Fab")
		)
		(fp_line
			(start 0.67945 0.3048)
			(end 0.120396 0.3048)
			(stroke
				(width 0.1)
				(type default)
			)
			(layer "F.Fab")
		)
		(fp_line
			(start -0.12065 0.2794)
			(end -0.12065 0.3048)
			(stroke
				(width 0.1)
				(type default)
			)
			(layer "F.Fab")
		)
		(fp_line
			(start 0.120396 0.2794)
			(end -0.12065 0.2794)
			(stroke
				(width 0.1)
				(type default)
			)
			(layer "F.Fab")
		)
		(fp_line
			(start -0.12065 -0.2794)
			(end 0.12065 -0.2794)
			(stroke
				(width 0.1)
				(type default)
			)
			(layer "F.Fab")
		)
		(fp_line
			(start 0.12065 -0.2794)
			(end 0.12065 -0.3048)
			(stroke
				(width 0.1)
				(type default)
			)
			(layer "F.Fab")
		)
		(fp_line
			(start 0.12065 -0.3048)
			(end 0.67945 -0.3048)
			(stroke
				(width 0.1)
				(type default)
			)
			(layer "F.Fab")
		)
		(fp_line
			(start 0.67945 -0.3048)
			(end 0.67945 0.3048)
			(stroke
				(width 0.1)
				(type default)
			)
			(layer "F.Fab")
		)
		(fp_line
			(start -0.67945 -0.305054)
			(end -0.12065 -0.305054)
			(stroke
				(width 0.1)
				(type default)
			)
			(layer "F.Fab")
		)
		(fp_line
			(start -0.12065 -0.305054)
			(end -0.12065 -0.2794)
			(stroke
				(width 0.1)
				(type default)
			)
			(layer "F.Fab")
		)
		(pad "1" smd circle
			(at -0.40005 0 270)
			(size 0 0)
			(layers "F.Cu" "F.Mask" "F.Paste")
			(net "P3V3_AUX")
		)
		(pad "2" smd circle
			(at 0.40005 0 270)
			(size 0 0)
			(layers "F.Cu" "F.Mask" "F.Paste")
			(net "FM_CPU1_PKGID0")
		)
	)
	(footprint ""
		(layer "F.Cu")
		(at 40.306498 -182.28564 180)
		(property "Reference" "C1404"
			(at 0 0 180)
			(layer "F.SilkS")
			(hide yes)
			(effects
				(font
					(size 1.27 1.27)
				)
			)
		)
		(property "Value" ""
			(at 0 0 180)
			(layer "F.Fab")
			(effects
				(font
					(size 1.27 1.27)
				)
			)
		)
		(duplicate_pad_numbers_are_jumpers no)
		(fp_line
			(start 1.524 0.762)
			(end -1.524 0.762)
			(stroke
				(width 0.1524)
				(type default)
			)
			(layer "F.SilkS")
		)
		(fp_line
			(start 1.524 -0.762)
			(end 1.524 0.762)
			(stroke
				(width 0.1524)
				(type default)
			)
			(layer "F.SilkS")
		)
		(fp_line
			(start -1.524 0.762)
			(end -1.524 -0.762)
			(stroke
				(width 0.1524)
				(type default)
			)
			(layer "F.SilkS")
		)
		(fp_line
			(start -1.524 -0.762)
			(end 1.524 -0.762)
			(stroke
				(width 0.1524)
				(type default)
			)
			(layer "F.SilkS")
		)
		(fp_line
			(start 1.1049 0.724916)
			(end 1.1049 -0.724916)
			(stroke
				(width 0.1)
				(type default)
			)
			(layer "F.Fab")
		)
		(fp_line
			(start 1.1049 -0.724916)
			(end -1.1049 -0.724916)
			(stroke
				(width 0.1)
				(type default)
			)
			(layer "F.Fab")
		)
		(fp_line
			(start -1.1049 0.724916)
			(end 1.1049 0.724916)
			(stroke
				(width 0.1)
				(type default)
			)
			(layer "F.Fab")
		)
		(fp_line
			(start -1.1049 -0.724916)
			(end -1.1049 0.724916)
			(stroke
				(width 0.1)
				(type default)
			)
			(layer "F.Fab")
		)
		(pad "1" smd rect
			(at -0.889 0)
			(size 1.016 1.27)
			(layers "F.Cu" "F.Mask" "F.Paste")
			(net "PVNN_MAIN_CPU1")
		)
		(pad "2" smd rect
			(at 0.889 0)
			(size 1.016 1.27)
			(layers "F.Cu" "F.Mask" "F.Paste")
			(net "GND")
		)
	)
	(footprint ""
		(layer "F.Cu")
		(at 111.25708 -397.874998 90)
		(property "Reference" "C1804"
			(at 0 0 90)
			(layer "F.SilkS")
			(hide yes)
			(effects
				(font
					(size 1.27 1.27)
				)
			)
		)
		(property "Value" ""
			(at 0 0 90)
			(layer "F.Fab")
			(effects
				(font
					(size 1.27 1.27)
				)
			)
		)
		(duplicate_pad_numbers_are_jumpers no)
		(fp_line
			(start 0.7874 -0.4064)
			(end 0.7874 0.4064)
			(stroke
				(width 0.1524)
				(type default)
			)
			(layer "F.SilkS")
		)
		(fp_line
			(start -0.7874 -0.4064)
			(end 0.7874 -0.4064)
			(stroke
				(width 0.1524)
				(type default)
			)
			(layer "F.SilkS")
		)
		(fp_line
			(start 0.7874 0.4064)
			(end -0.7874 0.4064)
			(stroke
				(width 0.1524)
				(type default)
			)
			(layer "F.SilkS")
		)
		(fp_line
			(start -0.7874 0.4064)
			(end -0.7874 -0.4064)
			(stroke
				(width 0.1524)
				(type default)
			)
			(layer "F.SilkS")
		)
		(fp_line
			(start -0.12065 -0.305054)
			(end -0.12065 -0.2794)
			(stroke
				(width 0.1)
				(type default)
			)
			(layer "F.Fab")
		)
		(fp_line
			(start -0.67945 -0.305054)
			(end -0.12065 -0.305054)
			(stroke
				(width 0.1)
				(type default)
			)
			(layer "F.Fab")
		)
		(fp_line
			(start 0.67945 -0.3048)
			(end 0.67945 0.3048)
			(stroke
				(width 0.1)
				(type default)
			)
			(layer "F.Fab")
		)
		(fp_line
			(start 0.12065 -0.3048)
			(end 0.67945 -0.3048)
			(stroke
				(width 0.1)
				(type default)
			)
			(layer "F.Fab")
		)
		(fp_line
			(start 0.12065 -0.2794)
			(end 0.12065 -0.3048)
			(stroke
				(width 0.1)
				(type default)
			)
			(layer "F.Fab")
		)
		(fp_line
			(start -0.12065 -0.2794)
			(end 0.12065 -0.2794)
			(stroke
				(width 0.1)
				(type default)
			)
			(layer "F.Fab")
		)
		(fp_line
			(start 0.120396 0.2794)
			(end -0.12065 0.2794)
			(stroke
				(width 0.1)
				(type default)
			)
			(layer "F.Fab")
		)
		(fp_line
			(start -0.12065 0.2794)
			(end -0.12065 0.3048)
			(stroke
				(width 0.1)
				(type default)
			)
			(layer "F.Fab")
		)
		(fp_line
			(start 0.67945 0.3048)
			(end 0.120396 0.3048)
			(stroke
				(width 0.1)
				(type default)
			)
			(layer "F.Fab")
		)
		(fp_line
			(start 0.120396 0.3048)
			(end 0.120396 0.2794)
			(stroke
				(width 0.1)
				(type default)
			)
			(layer "F.Fab")
		)
		(fp_line
			(start -0.12065 0.3048)
			(end -0.67945 0.3048)
			(stroke
				(width 0.1)
				(type default)
			)
			(layer "F.Fab")
		)
		(fp_line
			(start -0.67945 0.3048)
			(end -0.67945 -0.305054)
			(stroke
				(width 0.1)
				(type default)
			)
			(layer "F.Fab")
		)
		(pad "1" smd circle
			(at -0.40005 0 90)
			(size 0 0)
			(layers "F.Cu" "F.Mask" "F.Paste")
			(net "FM_SMB_2_ALERT_GPU_ISO_N")
		)
		(pad "2" smd circle
			(at 0.40005 0 90)
			(size 0 0)
			(layers "F.Cu" "F.Mask" "F.Paste")
			(net "GND")
		)
	)
	(footprint ""
		(layer "F.Cu")
		(at 60.25388 -16.220948 -90)
		(property "Reference" "R3172"
			(at 0 0 270)
			(layer "F.SilkS")
			(hide yes)
			(effects
				(font
					(size 1.27 1.27)
				)
			)
		)
		(property "Value" ""
			(at 0 0 270)
			(layer "F.Fab")
			(effects
				(font
					(size 1.27 1.27)
				)
			)
		)
		(duplicate_pad_numbers_are_jumpers no)
		(fp_line
			(start -0.7874 0.4064)
			(end -0.7874 -0.4064)
			(stroke
				(width 0.1524)
				(type default)
			)
			(layer "F.SilkS")
		)
		(fp_line
			(start 0.7874 0.4064)
			(end -0.7874 0.4064)
			(stroke
				(width 0.1524)
				(type default)
			)
			(layer "F.SilkS")
		)
		(fp_line
			(start -0.7874 -0.4064)
			(end 0.7874 -0.4064)
			(stroke
				(width 0.1524)
				(type default)
			)
			(layer "F.SilkS")
		)
		(fp_line
			(start 0.7874 -0.4064)
			(end 0.7874 0.4064)
			(stroke
				(width 0.1524)
				(type default)
			)
			(layer "F.SilkS")
		)
		(fp_line
			(start -0.67945 0.3048)
			(end -0.67945 -0.305054)
			(stroke
				(width 0.1)
				(type default)
			)
			(layer "F.Fab")
		)
		(fp_line
			(start -0.12065 0.3048)
			(end -0.67945 0.3048)
			(stroke
				(width 0.1)
				(type default)
			)
			(layer "F.Fab")
		)
		(fp_line
			(start 0.120396 0.3048)
			(end 0.120396 0.2794)
			(stroke
				(width 0.1)
				(type default)
			)
			(layer "F.Fab")
		)
		(fp_line
			(start 0.67945 0.3048)
			(end 0.120396 0.3048)
			(stroke
				(width 0.1)
				(type default)
			)
			(layer "F.Fab")
		)
		(fp_line
			(start -0.12065 0.2794)
			(end -0.12065 0.3048)
			(stroke
				(width 0.1)
				(type default)
			)
			(layer "F.Fab")
		)
		(fp_line
			(start 0.120396 0.2794)
			(end -0.12065 0.2794)
			(stroke
				(width 0.1)
				(type default)
			)
			(layer "F.Fab")
		)
		(fp_line
			(start -0.12065 -0.2794)
			(end 0.12065 -0.2794)
			(stroke
				(width 0.1)
				(type default)
			)
			(layer "F.Fab")
		)
		(fp_line
			(start 0.12065 -0.2794)
			(end 0.12065 -0.3048)
			(stroke
				(width 0.1)
				(type default)
			)
			(layer "F.Fab")
		)
		(fp_line
			(start 0.12065 -0.3048)
			(end 0.67945 -0.3048)
			(stroke
				(width 0.1)
				(type default)
			)
			(layer "F.Fab")
		)
		(fp_line
			(start 0.67945 -0.3048)
			(end 0.67945 0.3048)
			(stroke
				(width 0.1)
				(type default)
			)
			(layer "F.Fab")
		)
		(fp_line
			(start -0.67945 -0.305054)
			(end -0.12065 -0.305054)
			(stroke
				(width 0.1)
				(type default)
			)
			(layer "F.Fab")
		)
		(fp_line
			(start -0.12065 -0.305054)
			(end -0.12065 -0.2794)
			(stroke
				(width 0.1)
				(type default)
			)
			(layer "F.Fab")
		)
		(pad "1" smd circle
			(at -0.40005 0 270)
			(size 0 0)
			(layers "F.Cu" "F.Mask" "F.Paste")
			(net "OCP_V3_2_AUX_PWR_EN")
		)
		(pad "2" smd circle
			(at 0.40005 0 270)
			(size 0 0)
			(layers "F.Cu" "F.Mask" "F.Paste")
			(net "OCP_V3_2_AUX_PWR_EN_R")
		)
	)
)
